(kicad_pcb
	(version 20260206)
	(generator "pcbnew")
	(generator_version "10.0")
	(general
		(thickness 1.6)
		(legacy_teardrops no)
	)
	(paper "A4")
	(title_block
		(title "04192023_DAF0TMB3IC0_F0TG_MB_C_brd_V02_OCP.brd")
		(comment 1 "Grand Teton / footprints 3469-3475 of 8354")
	)
	(layers
		(0 "F.Cu" signal "TOP")
		(4 "In1.Cu" signal "GND")
		(6 "In2.Cu" signal "IN1")
		(8 "In3.Cu" signal "GND1")
		(10 "In4.Cu" signal "IN2")
		(12 "In5.Cu" signal "GND2")
		(14 "In6.Cu" signal "IN3")
		(16 "In7.Cu" signal "GND3")
		(18 "In8.Cu" signal "VCC")
		(20 "In9.Cu" signal "VCC1")
		(22 "In10.Cu" signal "GND4")
		(24 "In11.Cu" signal "IN4")
		(26 "In12.Cu" signal "GND5")
		(28 "In13.Cu" signal "IN5")
		(30 "In14.Cu" signal "GND6")
		(32 "In15.Cu" signal "IN6")
		(34 "In16.Cu" signal "GND7")
		(2 "B.Cu" signal "BOTTOM")
		(9 "F.Adhes" user "F.Adhesive")
		(11 "B.Adhes" user "B.Adhesive")
		(13 "F.Paste" user "Package Geometry/Pastemask Top")
		(15 "B.Paste" user "Package Geometry/Pastemask Bottom")
		(5 "F.SilkS" user "Ref Des/Silkscreen Top")
		(7 "B.SilkS" user "Ref Des/Silkscreen Bottom")
		(1 "F.Mask" user "Board Geometry/Soldermask Top")
		(3 "B.Mask" user "Board Geometry/Soldermask Bottom")
		(17 "Dwgs.User" user "User.Drawings")
		(19 "Cmts.User" user "User.Comments")
		(21 "Eco1.User" user "User.Eco1")
		(23 "Eco2.User" user "User.Eco2")
		(25 "Edge.Cuts" user "Board Geometry/Outline")
		(27 "Margin" user)
		(31 "F.CrtYd" user "Package Geometry/Place Bound Top")
		(29 "B.CrtYd" user "Package Geometry/Place Bound Bottom")
		(35 "F.Fab" user "Ref Des/Assembly Top")
		(33 "B.Fab" user "Ref Des/Assembly Bottom")
	)
	(footprint ""
		(layer "F.Cu")
		(at 75.081638 -337.658202 90)
		(property "Reference" "PC370"
			(at 0 0 90)
			(layer "F.SilkS")
			(hide yes)
			(effects
				(font
					(size 1.27 1.27)
				)
			)
		)
		(property "Value" ""
			(at 0 0 90)
			(layer "F.Fab")
			(effects
				(font
					(size 1.27 1.27)
				)
			)
		)
		(duplicate_pad_numbers_are_jumpers no)
		(fp_line
			(start 0.7874 -0.4064)
			(end 0.7874 0.4064)
			(stroke
				(width 0.1524)
				(type default)
			)
			(layer "F.SilkS")
		)
		(fp_line
			(start -0.7874 -0.4064)
			(end 0.7874 -0.4064)
			(stroke
				(width 0.1524)
				(type default)
			)
			(layer "F.SilkS")
		)
		(fp_line
			(start 0.7874 0.4064)
			(end 0.415798 0.4064)
			(stroke
				(width 0.1524)
				(type default)
			)
			(layer "F.SilkS")
		)
		(fp_line
			(start -0.447802 0.4064)
			(end -0.7874 0.4064)
			(stroke
				(width 0.1524)
				(type default)
			)
			(layer "F.SilkS")
		)
		(fp_line
			(start -0.7874 0.4064)
			(end -0.7874 -0.4064)
			(stroke
				(width 0.1524)
				(type default)
			)
			(layer "F.SilkS")
		)
		(fp_line
			(start -0.12065 -0.305054)
			(end -0.12065 -0.2794)
			(stroke
				(width 0.1)
				(type default)
			)
			(layer "F.Fab")
		)
		(fp_line
			(start -0.67945 -0.305054)
			(end -0.12065 -0.305054)
			(stroke
				(width 0.1)
				(type default)
			)
			(layer "F.Fab")
		)
		(fp_line
			(start 0.67945 -0.3048)
			(end 0.67945 0.3048)
			(stroke
				(width 0.1)
				(type default)
			)
			(layer "F.Fab")
		)
		(fp_line
			(start 0.12065 -0.3048)
			(end 0.67945 -0.3048)
			(stroke
				(width 0.1)
				(type default)
			)
			(layer "F.Fab")
		)
		(fp_line
			(start 0.12065 -0.2794)
			(end 0.12065 -0.3048)
			(stroke
				(width 0.1)
				(type default)
			)
			(layer "F.Fab")
		)
		(fp_line
			(start -0.12065 -0.2794)
			(end 0.12065 -0.2794)
			(stroke
				(width 0.1)
				(type default)
			)
			(layer "F.Fab")
		)
		(fp_line
			(start 0.120396 0.2794)
			(end -0.12065 0.2794)
			(stroke
				(width 0.1)
				(type default)
			)
			(layer "F.Fab")
		)
		(fp_line
			(start -0.12065 0.2794)
			(end -0.12065 0.3048)
			(stroke
				(width 0.1)
				(type default)
			)
			(layer "F.Fab")
		)
		(fp_line
			(start 0.67945 0.3048)
			(end 0.120396 0.3048)
			(stroke
				(width 0.1)
				(type default)
			)
			(layer "F.Fab")
		)
		(fp_line
			(start 0.120396 0.3048)
			(end 0.120396 0.2794)
			(stroke
				(width 0.1)
				(type default)
			)
			(layer "F.Fab")
		)
		(fp_line
			(start -0.12065 0.3048)
			(end -0.67945 0.3048)
			(stroke
				(width 0.1)
				(type default)
			)
			(layer "F.Fab")
		)
		(fp_line
			(start -0.67945 0.3048)
			(end -0.67945 -0.305054)
			(stroke
				(width 0.1)
				(type default)
			)
			(layer "F.Fab")
		)
		(pad "1" smd circle
			(at -0.40005 0 90)
			(size 0 0)
			(layers "F.Cu" "F.Mask" "F.Paste")
			(net "PVDDCR_CPU1_P1_VCC2")
		)
		(pad "2" smd circle
			(at 0.40005 0 90)
			(size 0 0)
			(layers "F.Cu" "F.Mask" "F.Paste")
			(net "GND")
		)
	)
	(footprint ""
		(layer "F.Cu")
		(at 425.54144 -438.214008 90)
		(property "Reference" "R2834"
			(at 0 0 90)
			(layer "F.SilkS")
			(hide yes)
			(effects
				(font
					(size 1.27 1.27)
				)
			)
		)
		(property "Value" ""
			(at 0 0 90)
			(layer "F.Fab")
			(effects
				(font
					(size 1.27 1.27)
				)
			)
		)
		(duplicate_pad_numbers_are_jumpers no)
		(fp_line
			(start 0.7874 -0.4064)
			(end 0.7874 0.4064)
			(stroke
				(width 0.1524)
				(type default)
			)
			(layer "F.SilkS")
		)
		(fp_line
			(start -0.7874 -0.4064)
			(end 0.7874 -0.4064)
			(stroke
				(width 0.1524)
				(type default)
			)
			(layer "F.SilkS")
		)
		(fp_line
			(start 0.7874 0.4064)
			(end -0.7874 0.4064)
			(stroke
				(width 0.1524)
				(type default)
			)
			(layer "F.SilkS")
		)
		(fp_line
			(start -0.7874 0.4064)
			(end -0.7874 -0.4064)
			(stroke
				(width 0.1524)
				(type default)
			)
			(layer "F.SilkS")
		)
		(fp_line
			(start -0.12065 -0.305054)
			(end -0.12065 -0.2794)
			(stroke
				(width 0.1)
				(type default)
			)
			(layer "F.Fab")
		)
		(fp_line
			(start -0.67945 -0.305054)
			(end -0.12065 -0.305054)
			(stroke
				(width 0.1)
				(type default)
			)
			(layer "F.Fab")
		)
		(fp_line
			(start 0.67945 -0.3048)
			(end 0.67945 0.3048)
			(stroke
				(width 0.1)
				(type default)
			)
			(layer "F.Fab")
		)
		(fp_line
			(start 0.12065 -0.3048)
			(end 0.67945 -0.3048)
			(stroke
				(width 0.1)
				(type default)
			)
			(layer "F.Fab")
		)
		(fp_line
			(start 0.12065 -0.2794)
			(end 0.12065 -0.3048)
			(stroke
				(width 0.1)
				(type default)
			)
			(layer "F.Fab")
		)
		(fp_line
			(start -0.12065 -0.2794)
			(end 0.12065 -0.2794)
			(stroke
				(width 0.1)
				(type default)
			)
			(layer "F.Fab")
		)
		(fp_line
			(start 0.120396 0.2794)
			(end -0.12065 0.2794)
			(stroke
				(width 0.1)
				(type default)
			)
			(layer "F.Fab")
		)
		(fp_line
			(start -0.12065 0.2794)
			(end -0.12065 0.3048)
			(stroke
				(width 0.1)
				(type default)
			)
			(layer "F.Fab")
		)
		(fp_line
			(start 0.67945 0.3048)
			(end 0.120396 0.3048)
			(stroke
				(width 0.1)
				(type default)
			)
			(layer "F.Fab")
		)
		(fp_line
			(start 0.120396 0.3048)
			(end 0.120396 0.2794)
			(stroke
				(width 0.1)
				(type default)
			)
			(layer "F.Fab")
		)
		(fp_line
			(start -0.12065 0.3048)
			(end -0.67945 0.3048)
			(stroke
				(width 0.1)
				(type default)
			)
			(layer "F.Fab")
		)
		(fp_line
			(start -0.67945 0.3048)
			(end -0.67945 -0.305054)
			(stroke
				(width 0.1)
				(type default)
			)
			(layer "F.Fab")
		)
		(pad "1" smd circle
			(at -0.40005 0 90)
			(size 0 0)
			(layers "F.Cu" "F.Mask" "F.Paste")
			(net "P3V3_AUX")
		)
		(pad "2" smd circle
			(at 0.40005 0 90)
			(size 0 0)
			(layers "F.Cu" "F.Mask" "F.Paste")
			(net "RST_BMC_FROM_SWB")
		)
	)
	(footprint ""
		(layer "F.Cu")
		(at 140.208 -114.554)
		(property "Reference" "R8120"
			(at 0 0 0)
			(layer "F.SilkS")
			(hide yes)
			(effects
				(font
					(size 1.27 1.27)
				)
			)
		)
		(property "Value" ""
			(at 0 0 0)
			(layer "F.Fab")
			(effects
				(font
					(size 1.27 1.27)
				)
			)
		)
		(duplicate_pad_numbers_are_jumpers no)
		(fp_line
			(start -0.7874 -0.4064)
			(end 0.7874 -0.4064)
			(stroke
				(width 0.1524)
				(type default)
			)
			(layer "F.SilkS")
		)
		(fp_line
			(start -0.7874 0.4064)
			(end -0.7874 -0.4064)
			(stroke
				(width 0.1524)
				(type default)
			)
			(layer "F.SilkS")
		)
		(fp_line
			(start 0.7874 -0.4064)
			(end 0.7874 0.4064)
			(stroke
				(width 0.1524)
				(type default)
			)
			(layer "F.SilkS")
		)
		(fp_line
			(start 0.7874 0.4064)
			(end -0.7874 0.4064)
			(stroke
				(width 0.1524)
				(type default)
			)
			(layer "F.SilkS")
		)
		(fp_line
			(start -0.67945 -0.305054)
			(end -0.12065 -0.305054)
			(stroke
				(width 0.1)
				(type default)
			)
			(layer "F.Fab")
		)
		(fp_line
			(start -0.67945 0.3048)
			(end -0.67945 -0.305054)
			(stroke
				(width 0.1)
				(type default)
			)
			(layer "F.Fab")
		)
		(fp_line
			(start -0.12065 -0.305054)
			(end -0.12065 -0.2794)
			(stroke
				(width 0.1)
				(type default)
			)
			(layer "F.Fab")
		)
		(fp_line
			(start -0.12065 -0.2794)
			(end 0.12065 -0.2794)
			(stroke
				(width 0.1)
				(type default)
			)
			(layer "F.Fab")
		)
		(fp_line
			(start -0.12065 0.2794)
			(end -0.12065 0.3048)
			(stroke
				(width 0.1)
				(type default)
			)
			(layer "F.Fab")
		)
		(fp_line
			(start -0.12065 0.3048)
			(end -0.67945 0.3048)
			(stroke
				(width 0.1)
				(type default)
			)
			(layer "F.Fab")
		)
		(fp_line
			(start 0.120396 0.2794)
			(end -0.12065 0.2794)
			(stroke
				(width 0.1)
				(type default)
			)
			(layer "F.Fab")
		)
		(fp_line
			(start 0.120396 0.3048)
			(end 0.120396 0.2794)
			(stroke
				(width 0.1)
				(type default)
			)
			(layer "F.Fab")
		)
		(fp_line
			(start 0.12065 -0.3048)
			(end 0.67945 -0.3048)
			(stroke
				(width 0.1)
				(type default)
			)
			(layer "F.Fab")
		)
		(fp_line
			(start 0.12065 -0.2794)
			(end 0.12065 -0.3048)
			(stroke
				(width 0.1)
				(type default)
			)
			(layer "F.Fab")
		)
		(fp_line
			(start 0.67945 -0.3048)
			(end 0.67945 0.3048)
			(stroke
				(width 0.1)
				(type default)
			)
			(layer "F.Fab")
		)
		(fp_line
			(start 0.67945 0.3048)
			(end 0.120396 0.3048)
			(stroke
				(width 0.1)
				(type default)
			)
			(layer "F.Fab")
		)
		(pad "1" smd circle
			(at -0.40005 0)
			(size 0 0)
			(layers "F.Cu" "F.Mask" "F.Paste")
			(net "P3V3_AUX")
		)
		(pad "2" smd circle
			(at 0.40005 0)
			(size 0 0)
			(layers "F.Cu" "F.Mask" "F.Paste")
			(net "UV_P2V5_COMP")
		)
	)
	(footprint ""
		(layer "F.Cu")
		(at 365.835692 -260.305042 180)
		(property "Reference" "C2139"
			(at 0 0 180)
			(layer "F.SilkS")
			(hide yes)
			(effects
				(font
					(size 1.27 1.27)
				)
			)
		)
		(property "Value" ""
			(at 0 0 180)
			(layer "F.Fab")
			(effects
				(font
					(size 1.27 1.27)
				)
			)
		)
		(duplicate_pad_numbers_are_jumpers no)
		(fp_line
			(start 0.7874 0.4064)
			(end -0.7874 0.4064)
			(stroke
				(width 0.1524)
				(type default)
			)
			(layer "F.SilkS")
		)
		(fp_line
			(start 0.7874 -0.4064)
			(end 0.7874 0.4064)
			(stroke
				(width 0.1524)
				(type default)
			)
			(layer "F.SilkS")
		)
		(fp_line
			(start -0.7874 0.4064)
			(end -0.7874 -0.4064)
			(stroke
				(width 0.1524)
				(type default)
			)
			(layer "F.SilkS")
		)
		(fp_line
			(start -0.7874 -0.4064)
			(end 0.7874 -0.4064)
			(stroke
				(width 0.1524)
				(type default)
			)
			(layer "F.SilkS")
		)
		(fp_line
			(start 0.67945 0.3048)
			(end 0.120396 0.3048)
			(stroke
				(width 0.1)
				(type default)
			)
			(layer "F.Fab")
		)
		(fp_line
			(start 0.67945 -0.3048)
			(end 0.67945 0.3048)
			(stroke
				(width 0.1)
				(type default)
			)
			(layer "F.Fab")
		)
		(fp_line
			(start 0.12065 -0.2794)
			(end 0.12065 -0.3048)
			(stroke
				(width 0.1)
				(type default)
			)
			(layer "F.Fab")
		)
		(fp_line
			(start 0.12065 -0.3048)
			(end 0.67945 -0.3048)
			(stroke
				(width 0.1)
				(type default)
			)
			(layer "F.Fab")
		)
		(fp_line
			(start 0.120396 0.3048)
			(end 0.120396 0.2794)
			(stroke
				(width 0.1)
				(type default)
			)
			(layer "F.Fab")
		)
		(fp_line
			(start 0.120396 0.2794)
			(end -0.12065 0.2794)
			(stroke
				(width 0.1)
				(type default)
			)
			(layer "F.Fab")
		)
		(fp_line
			(start -0.12065 0.3048)
			(end -0.67945 0.3048)
			(stroke
				(width 0.1)
				(type default)
			)
			(layer "F.Fab")
		)
		(fp_line
			(start -0.12065 0.2794)
			(end -0.12065 0.3048)
			(stroke
				(width 0.1)
				(type default)
			)
			(layer "F.Fab")
		)
		(fp_line
			(start -0.12065 -0.2794)
			(end 0.12065 -0.2794)
			(stroke
				(width 0.1)
				(type default)
			)
			(layer "F.Fab")
		)
		(fp_line
			(start -0.12065 -0.305054)
			(end -0.12065 -0.2794)
			(stroke
				(width 0.1)
				(type default)
			)
			(layer "F.Fab")
		)
		(fp_line
			(start -0.67945 0.3048)
			(end -0.67945 -0.305054)
			(stroke
				(width 0.1)
				(type default)
			)
			(layer "F.Fab")
		)
		(fp_line
			(start -0.67945 -0.305054)
			(end -0.12065 -0.305054)
			(stroke
				(width 0.1)
				(type default)
			)
			(layer "F.Fab")
		)
		(pad "1" smd circle
			(at -0.40005 0 180)
			(size 0 0)
			(layers "F.Cu" "F.Mask" "F.Paste")
			(net "PVDDCR_SOC_P0")
		)
		(pad "2" smd circle
			(at 0.40005 0 180)
			(size 0 0)
			(layers "F.Cu" "F.Mask" "F.Paste")
			(net "GND")
		)
	)
	(footprint ""
		(layer "F.Cu")
		(at 143.46047 -80.977486 180)
		(property "Reference" "PC6008"
			(at 0 0 180)
			(layer "F.SilkS")
			(hide yes)
			(effects
				(font
					(size 1.27 1.27)
				)
			)
		)
		(property "Value" ""
			(at 0 0 180)
			(layer "F.Fab")
			(effects
				(font
					(size 1.27 1.27)
				)
			)
		)
		(duplicate_pad_numbers_are_jumpers no)
		(fp_line
			(start 0.7874 0.4064)
			(end -0.7874 0.4064)
			(stroke
				(width 0.1524)
				(type default)
			)
			(layer "F.SilkS")
		)
		(fp_line
			(start 0.7874 -0.4064)
			(end 0.7874 0.4064)
			(stroke
				(width 0.1524)
				(type default)
			)
			(layer "F.SilkS")
		)
		(fp_line
			(start -0.7874 0.4064)
			(end -0.7874 -0.4064)
			(stroke
				(width 0.1524)
				(type default)
			)
			(layer "F.SilkS")
		)
		(fp_line
			(start -0.7874 -0.4064)
			(end 0.7874 -0.4064)
			(stroke
				(width 0.1524)
				(type default)
			)
			(layer "F.SilkS")
		)
		(fp_line
			(start 0.67945 0.3048)
			(end 0.120396 0.3048)
			(stroke
				(width 0.1)
				(type default)
			)
			(layer "F.Fab")
		)
		(fp_line
			(start 0.67945 -0.3048)
			(end 0.67945 0.3048)
			(stroke
				(width 0.1)
				(type default)
			)
			(layer "F.Fab")
		)
		(fp_line
			(start 0.12065 -0.2794)
			(end 0.12065 -0.3048)
			(stroke
				(width 0.1)
				(type default)
			)
			(layer "F.Fab")
		)
		(fp_line
			(start 0.12065 -0.3048)
			(end 0.67945 -0.3048)
			(stroke
				(width 0.1)
				(type default)
			)
			(layer "F.Fab")
		)
		(fp_line
			(start 0.120396 0.3048)
			(end 0.120396 0.2794)
			(stroke
				(width 0.1)
				(type default)
			)
			(layer "F.Fab")
		)
		(fp_line
			(start 0.120396 0.2794)
			(end -0.12065 0.2794)
			(stroke
				(width 0.1)
				(type default)
			)
			(layer "F.Fab")
		)
		(fp_line
			(start -0.12065 0.3048)
			(end -0.67945 0.3048)
			(stroke
				(width 0.1)
				(type default)
			)
			(layer "F.Fab")
		)
		(fp_line
			(start -0.12065 0.2794)
			(end -0.12065 0.3048)
			(stroke
				(width 0.1)
				(type default)
			)
			(layer "F.Fab")
		)
		(fp_line
			(start -0.12065 -0.2794)
			(end 0.12065 -0.2794)
			(stroke
				(width 0.1)
				(type default)
			)
			(layer "F.Fab")
		)
		(fp_line
			(start -0.12065 -0.305054)
			(end -0.12065 -0.2794)
			(stroke
				(width 0.1)
				(type default)
			)
			(layer "F.Fab")
		)
		(fp_line
			(start -0.67945 0.3048)
			(end -0.67945 -0.305054)
			(stroke
				(width 0.1)
				(type default)
			)
			(layer "F.Fab")
		)
		(fp_line
			(start -0.67945 -0.305054)
			(end -0.12065 -0.305054)
			(stroke
				(width 0.1)
				(type default)
			)
			(layer "F.Fab")
		)
		(pad "1" smd circle
			(at -0.40005 0 180)
			(size 0 0)
			(layers "F.Cu" "F.Mask" "F.Paste")
			(net "P1V8_AUX_VCC")
		)
		(pad "2" smd circle
			(at 0.40005 0 180)
			(size 0 0)
			(layers "F.Cu" "F.Mask" "F.Paste")
			(net "GND")
		)
	)
	(footprint ""
		(layer "F.Cu")
		(at 391.268458 -404.0124 -90)
		(property "Reference" "R1088"
			(at 0 0 270)
			(layer "F.SilkS")
			(hide yes)
			(effects
				(font
					(size 1.27 1.27)
				)
			)
		)
		(property "Value" ""
			(at 0 0 270)
			(layer "F.Fab")
			(effects
				(font
					(size 1.27 1.27)
				)
			)
		)
		(duplicate_pad_numbers_are_jumpers no)
		(fp_line
			(start -0.32512 0.175006)
			(end -0.32512 -0.175006)
			(stroke
				(width 0.1)
				(type default)
			)
			(layer "F.Fab")
		)
		(fp_line
			(start 0.32512 0.175006)
			(end -0.32512 0.175006)
			(stroke
				(width 0.1)
				(type default)
			)
			(layer "F.Fab")
		)
		(fp_line
			(start -0.32512 -0.175006)
			(end 0.32512 -0.175006)
			(stroke
				(width 0.1)
				(type default)
			)
			(layer "F.Fab")
		)
		(fp_line
			(start 0.32512 -0.175006)
			(end 0.32512 0.175006)
			(stroke
				(width 0.1)
				(type default)
			)
			(layer "F.Fab")
		)
		(pad "1" smd rect
			(at -0.2667 0 270)
			(size 0.3048 0.381)
			(layers "F.Cu" "F.Mask" "F.Paste")
			(net "RST_RT_CPU0_P3_PERST_N")
		)
		(pad "2" smd rect
			(at 0.2667 0 90)
			(size 0.3048 0.381)
			(layers "F.Cu" "F.Mask" "F.Paste")
			(net "RST_RT_CPU0_P3_PERST_R_N")
		)
	)
	(footprint ""
		(layer "F.Cu")
		(at 412.481268 -71.812912)
		(property "Reference" "R1135"
			(at 0 0 0)
			(layer "F.SilkS")
			(hide yes)
			(effects
				(font
					(size 1.27 1.27)
				)
			)
		)
		(property "Value" ""
			(at 0 0 0)
			(layer "F.Fab")
			(effects
				(font
					(size 1.27 1.27)
				)
			)
		)
		(duplicate_pad_numbers_are_jumpers no)
		(fp_line
			(start -0.7874 -0.4064)
			(end 0.7874 -0.4064)
			(stroke
				(width 0.1524)
				(type default)
			)
			(layer "F.SilkS")
		)
		(fp_line
			(start -0.7874 0.4064)
			(end -0.7874 -0.4064)
			(stroke
				(width 0.1524)
				(type default)
			)
			(layer "F.SilkS")
		)
		(fp_line
			(start 0.7874 -0.4064)
			(end 0.7874 0.4064)
			(stroke
				(width 0.1524)
				(type default)
			)
			(layer "F.SilkS")
		)
		(fp_line
			(start 0.7874 0.4064)
			(end -0.7874 0.4064)
			(stroke
				(width 0.1524)
				(type default)
			)
			(layer "F.SilkS")
		)
		(fp_line
			(start -0.67945 -0.305054)
			(end -0.12065 -0.305054)
			(stroke
				(width 0.1)
				(type default)
			)
			(layer "F.Fab")
		)
		(fp_line
			(start -0.67945 0.3048)
			(end -0.67945 -0.305054)
			(stroke
				(width 0.1)
				(type default)
			)
			(layer "F.Fab")
		)
		(fp_line
			(start -0.12065 -0.305054)
			(end -0.12065 -0.2794)
			(stroke
				(width 0.1)
				(type default)
			)
			(layer "F.Fab")
		)
		(fp_line
			(start -0.12065 -0.2794)
			(end 0.12065 -0.2794)
			(stroke
				(width 0.1)
				(type default)
			)
			(layer "F.Fab")
		)
		(fp_line
			(start -0.12065 0.2794)
			(end -0.12065 0.3048)
			(stroke
				(width 0.1)
				(type default)
			)
			(layer "F.Fab")
		)
		(fp_line
			(start -0.12065 0.3048)
			(end -0.67945 0.3048)
			(stroke
				(width 0.1)
				(type default)
			)
			(layer "F.Fab")
		)
		(fp_line
			(start 0.120396 0.2794)
			(end -0.12065 0.2794)
			(stroke
				(width 0.1)
				(type default)
			)
			(layer "F.Fab")
		)
		(fp_line
			(start 0.120396 0.3048)
			(end 0.120396 0.2794)
			(stroke
				(width 0.1)
				(type default)
			)
			(layer "F.Fab")
		)
		(fp_line
			(start 0.12065 -0.3048)
			(end 0.67945 -0.3048)
			(stroke
				(width 0.1)
				(type default)
			)
			(layer "F.Fab")
		)
		(fp_line
			(start 0.12065 -0.2794)
			(end 0.12065 -0.3048)
			(stroke
				(width 0.1)
				(type default)
			)
			(layer "F.Fab")
		)
		(fp_line
			(start 0.67945 -0.3048)
			(end 0.67945 0.3048)
			(stroke
				(width 0.1)
				(type default)
			)
			(layer "F.Fab")
		)
		(fp_line
			(start 0.67945 0.3048)
			(end 0.120396 0.3048)
			(stroke
				(width 0.1)
				(type default)
			)
			(layer "F.Fab")
		)
		(pad "1" smd circle
			(at -0.40005 0)
			(size 0 0)
			(layers "F.Cu" "F.Mask" "F.Paste")
			(net "HP_LVC3_OCP_V3_1_R_EN")
		)
		(pad "2" smd circle
			(at 0.40005 0)
			(size 0 0)
			(layers "F.Cu" "F.Mask" "F.Paste")
			(net "HP_LVC3_OCP_V3_1_P12V_PWRGD")
		)
	)
)
